FILE_TYPE = CONNECTIVITY;
{Allegro Design Entry HDL 16.6-p007 (v16-6-112F) 10/10/2012}
"PAGE_NUMBER" = 247;
0"NC";
1"P3V3_STBY\g";
2"GND\g";
3"GND\g";
4"GND\g";
5"GND\g";
6"P3V3_STBY\g";
7"GND\g";
8"P3V3_STBY\g";
9"GND\g";
10"GND\g";
11"GND\g";
12"P3V3_STBY\g";
13"GND\g";
14"GND\g";
15"P3V3_STBY\g";
16"P3V3_STBY\g";
17"PCA9555_A2";
18"LED_POSTCODE_5_R";
19"SMB_BMC_PMBUS_STBY_LVC3_SCL"CDS_PHYS_NET_NAME"SMB_BMC_PMBUS_STBY_LVC3_SCL";
20"LED_POSTCODE_7_R";
21"PCA9555_INT_N";
22"PCA9555_A1";
23"LED_POSTCODE_0_R";
24"LED_POSTCODE_1_R";
25"LED_POSTCODE_2_R";
26"LED_POSTCODE_3_R";
27"LED_POSTCODE_4_R";
28"LED_POSTCODE_6_R";
29"FM_DEBUG_RST_BTN_N";
30"FP_PWR_BTN_R_N";
31"PCA9555_A0";
32"SMB_IPMB_3V3AUX_SCL";
33"SMB_IPMB_3V3AUX_SDA";
34"PCA9555_INT_N";
35"SMB_IPMB_3V3AUX_SDA";
36"PCA9555_A2";
37"SMB_HOST_STBY_LVC3_SDA";
38"SMB_HOST_STBY_LVC3_SCL_R3";
39"SMB_HOST_STBY_LVC3_SDA_R3";
40"PU_ID_EEPROM_A2";
41"PD_ID_EEPROM_WP";
42"HSC_SMBUS_SWITCH_EN";
43"SMB_HOST_STBY_LVC3_SCL";
44"SMB_BMC_PMBUS_STBY_LVC3_SDA"CDS_PHYS_NET_NAME"SMB_BMC_PMBUS_STBY_LVC3_SDA";
45"SMB_PMBUS_BMC_STBY_LVC3_SDA_R1"CDS_PHYS_NET_NAME"SMB_PMBUS_BMC_STBY_LVC3_SDA_R1";
46"SMB_PMBUS_BMC_STBY_LVC3_SCL_R1"CDS_PHYS_NET_NAME"SMB_PMBUS_BMC_STBY_LVC3_SCL_R1";
47"SMB_IPMB_3V3AUX_SCL";
48"PCA9555_A0";
49"PCA9555_A1";
%"RES"
"2","(-7375,3800)","2","mstr_discrete","I1";
;
CDS_SEC"1"
$SEC"1"
CDS_LOCATION"R6W10"
ROOM"CPU_FANS"
BOM_COST"SM_THERM"
CDS_LIB"mstr_discrete"
PART_NUMBER"G21796-072"
TOLERANCE"1%"
LOCATION"R6W10"
VALUE"4.75K"
WATTAGE"1/16W"
MATERIAL"CHIP"
PACK_TYPE"0402";
"A"
$PN"1"1;
"B"
$PN"2"34;
%"RES"
"2","(-5250,4050)","0","mstr_discrete","I10";
;
CDS_SEC"1"
$SEC"1"
CDS_LOCATION"R6W5"
ROOM"HOT_SWAP"
NO_XNET_CONNECTION"1"
CDS_LIB"mstr_discrete"
PACK_TYPE"0402"
WATTAGE"1/16W"
MATERIAL"EMPTY"
PART_NUMBER"G21796-072"
VALUE"4.75K"
TOLERANCE"1%"
LOCATION"R6W5";
"A"
$PN"1"6;
"B"
$PN"2"49;
%"RES"
"2","(-4850,4050)","0","mstr_discrete","I11";
;
CDS_SEC"1"
$SEC"1"
CDS_LOCATION"R6W6"
NO_XNET_CONNECTION"1"
ROOM"HOT_SWAP"
CDS_LIB"mstr_discrete"
PART_NUMBER"G21796-072"
PACK_TYPE"0402"
MATERIAL"EMPTY"
VALUE"4.75K"
TOLERANCE"1%"
WATTAGE"1/16W"
LOCATION"R6W6";
"A"
$PN"1"6;
"B"
$PN"2"48;
%"P3V3_STBY"
"1","(-7375,4325)","0","mstr_symbols","I12";
;
CDS_LIB"mstr_symbols"
SIZE"1B"
VOLTAGE"3.3V"
BODY_TYPE"PLUMBING"
HDL_POWER"P3V3_STBY";
"G\NAC"1;
%"GND"
"1","(-4850,3150)","0","mstr_symbols","I13";
;
SIZE"1B"
CDS_LIB"mstr_symbols"
VOLTAGE"0.0V"
BODY_TYPE"PLUMBING"
HDL_POWER"GND";
"A\NAC"2;
%"GND"
"1","(-3600,3750)","0","mstr_symbols","I17";
;
CDS_LIB"mstr_symbols"
SIZE"1B"
VOLTAGE"0.0V"
BODY_TYPE"PLUMBING"
HDL_POWER"GND";
"A\NAC"3;
%"CAP"
"1","(-3600,3950)","0","mstr_discrete","I18";
;
CDS_SEC"1"
$SEC"1"
CDS_LOCATION"C6W1"
CDS_LIB"mstr_discrete"
BOM_COST"SM_THERM"
ROOM"CPUFANS"
LOCATION"C6W1"
VALUE"0.1UF"
VOLTAGE"16V"
PART_NUMBER"A36096-030"
MATERIAL"X7R"
TOLERANCE"10%"
PACK_TYPE"0402LF";
"A"
$PN"1"16;
"B"
$PN"2"3;
%"P3V3_STBY"
"1","(-3600,4325)","0","mstr_symbols","I19";
;
CDS_LIB"mstr_symbols"
SIZE"1B"
VOLTAGE"3.3V"
BODY_TYPE"PLUMBING"
HDL_POWER"P3V3_STBY";
"G\NAC"16;
%"GND"
"1","(-1900,3000)","0","mstr_symbols","I20";
;
CDS_LIB"mstr_symbols"
SIZE"1B"
VOLTAGE"0.0V"
BODY_TYPE"PLUMBING"
HDL_POWER"GND";
"A\NAC"4;
%"RES"
"2","(-5650,3425)","2","mstr_discrete","I3";
;
CDS_SEC"1"
$SEC"1"
CDS_LOCATION"R6W7"
BOM_COST"SM_THERM"
ROOM"CPU_FANS"
CDS_LIB"mstr_discrete"
LOCATION"R6W7"
VALUE"4.75K"
TOLERANCE"1%"
WATTAGE"1/16W"
MATERIAL"CHIP"
PACK_TYPE"0402"
PART_NUMBER"G21796-072";
"A"
$PN"1"36;
"B"
$PN"2"5;
%"GND"
"1","(-5650,3175)","0","mstr_symbols","I4";
;
SIZE"1B"
CDS_LIB"mstr_symbols"
VOLTAGE"0.0V"
BODY_TYPE"PLUMBING"
HDL_POWER"GND";
"A\NAC"5;
%"RES"
"2","(-5650,4050)","0","mstr_discrete","I5";
;
CDS_SEC"1"
$SEC"1"
CDS_LOCATION"R6W4"
CDS_LIB"mstr_discrete"
ROOM"HOT_SWAP"
NO_XNET_CONNECTION"1"
PART_NUMBER"G21796-072"
PACK_TYPE"0402"
WATTAGE"1/16W"
LOCATION"R6W4"
VALUE"4.75K"
TOLERANCE"1%"
MATERIAL"EMPTY";
"A"
$PN"1"6;
"B"
$PN"2"36;
%"P3V3_STBY"
"1","(-5650,4325)","0","mstr_symbols","I6";
;
SIZE"1B"
CDS_LIB"mstr_symbols"
VOLTAGE"3.3V"
BODY_TYPE"PLUMBING"
HDL_POWER"P3V3_STBY";
"G\NAC"6;
%"RES"
"2","(-7150,3800)","0","mstr_discrete","I67";
;
CDS_SEC"1"
$SEC"1"
CDS_LOCATION"R6W11"
NO_XNET_CONNECTION"1"
ROOM"HOT_SWAP"
CDS_LIB"mstr_discrete"
PART_NUMBER"G21796-072"
PACK_TYPE"0402"
TOLERANCE"1%"
WATTAGE"1/16W"
MATERIAL"EMPTY"
LOCATION"R6W11"
VALUE"4.75K";
"A"
$PN"1"1;
"B"
$PN"2"47;
%"RES"
"2","(-6850,3800)","0","mstr_discrete","I68";
;
CDS_SEC"1"
$SEC"1"
CDS_LOCATION"R6W12"
NO_XNET_CONNECTION"1"
ROOM"HOT_SWAP"
CDS_LIB"mstr_discrete"
PART_NUMBER"G21796-072"
MATERIAL"EMPTY"
WATTAGE"1/16W"
VALUE"4.75K"
TOLERANCE"1%"
PACK_TYPE"0402"
LOCATION"R6W12";
"A"
$PN"1"1;
"B"
$PN"2"35;
%"GND"
"1","(-5250,3175)","0","mstr_symbols","I7";
;
SIZE"1B"
CDS_LIB"mstr_symbols"
VOLTAGE"0.0V"
BODY_TYPE"PLUMBING"
HDL_POWER"GND";
"A\NAC"7;
%"P3V3_STBY"
"1","(-6100,2325)","0","mstr_symbols","I73";
;
SIZE"1B"
BODY_TYPE"PLUMBING"
VOLTAGE"3.3V"
HDL_POWER"P3V3_STBY"
CDS_LIB"mstr_symbols";
"G\NAC"8;
%"PCA9515ADGKR-1-GP"
"1","(-6475,1625)","0","w_hdl","I77";
;
CDS_SEC"1"
$SEC"1"
CDS_LOCATION"U6W2"
CDS_LMAN_SYM_OUTLINE"-225,175,225,-175"
CDS_LIB"w_hdl"
PACK_TYPE"DISCRET-G5"
VALUE"PCA9515ADGKR-1-GP"
PART_NUMBER"71.09515.F0W"
LOCATION"U6W2";
"VCC"
$PN"8"8;
"SCL1"
$PN"7"19;
"SDA1"
$PN"6"44;
"EN"
$PN"5"42;
"GND"
$PN"4"9;
"SDA0"
$PN"3"45;
"SCL0"
$PN"2"46;
"NC#1"
$PN"1"0;
%"GND"
"1","(-6850,1300)","0","mstr_symbols","I78";
;
CDS_LIB"mstr_symbols"
SIZE"1B"
HDL_POWER"GND"
BODY_TYPE"PLUMBING"
VOLTAGE"0.0V";
"A\NAC"9;
%"RES"
"2","(-5250,3425)","2","mstr_discrete","I8";
;
CDS_SEC"1"
$SEC"1"
CDS_LOCATION"R6W8"
BOM_COST"SM_THERM"
ROOM"CPU_FANS"
CDS_LIB"mstr_discrete"
PART_NUMBER"G21796-072"
TOLERANCE"1%"
PACK_TYPE"0402"
WATTAGE"1/16W"
MATERIAL"CHIP"
LOCATION"R6W8"
VALUE"4.75K";
"A"
$PN"1"49;
"B"
$PN"2"7;
%"CAP"
"1","(-5900,2075)","0","mstr_discrete","I81";
;
CDS_SEC"1"
$SEC"1"
CDS_LOCATION"C6W2"
BOM_COST"SM_THERM"
ROOM"CPUFANS"
CDS_LIB"mstr_discrete"
PACK_TYPE"0402LF"
PART_NUMBER"A36096-030"
LOCATION"C6W2"
VALUE"0.1UF"
VOLTAGE"16V"
MATERIAL"X7R"
TOLERANCE"10%";
"A"
$PN"1"8;
"B"
$PN"2"10;
%"GND"
"1","(-5900,1725)","0","mstr_symbols","I82";
;
CDS_LIB"mstr_symbols"
SIZE"1B"
HDL_POWER"GND"
BODY_TYPE"PLUMBING"
VOLTAGE"0.0V";
"A\NAC"10;
%"P3V3_STBY"
"1","(-1775,2550)","0","mstr_symbols","I83";
;
HDL_POWER"P3V3_STBY"
VOLTAGE"3.3V"
CDS_LIB"mstr_symbols"
SIZE"1B"
BODY_TYPE"PLUMBING";
"G\NAC"15;
%"CAP_A"
"1","(-1775,2300)","0","dev_discrete","I85";
;
CDS_LOCATION"C6W3"
CDS_LIB"dev_discrete"
CDS_SEC"1"
ROOM"TEMP_SENSORS"
SEC"1"
SEC_TYPE"0402V"
BOM_COST"SM_THERM"
VOLTAGE"16V"
VALUE"0.1UF"
LOCATION"C6W3"
PACK_TYPE"0402V"
PART_NUMBER"A36096-030"
MATERIAL"X7R"
TOLERANCE"10%";
"B"
$PN"2"11;
"A"
$PN"1"15;
%"GND"
"1","(-1775,1975)","0","mstr_symbols","I86";
;
BODY_TYPE"PLUMBING"
SIZE"1B"
VOLTAGE"0.0V"
HDL_POWER"GND"
CDS_LIB"mstr_symbols";
"A\NAC"11;
%"RES"
"1","(-1050,1750)","0","mstr_discrete","I87";
;
CDS_LOCATION"R6W20"
ROOM"TEMP_SENSORS"
$SEC"1"
CDS_SEC"1"
BOM_COST"SM_THERM"
CDS_LIB"mstr_discrete"
WATTAGE"1/16W"
PART_NUMBER"G21796-173"
PACK_TYPE"0402"
MATERIAL"CHIP"
TOLERANCE"1%"
VALUE"20.0"
LOCATION"R6W20";
"B"
$PN"2"37;
"A"
$PN"1"39;
%"P3V3_STBY"
"1","(-3000,2500)","0","mstr_symbols","I88";
;
SIZE"1B"
BODY_TYPE"PLUMBING"
VOLTAGE"3.3V"
CDS_LIB"mstr_symbols"
HDL_POWER"P3V3_STBY";
"G\NAC"12;
%"AT24C64"
"1","(-2200,1850)","0","mstr_memory","I89";
;
CDS_SEC"1"
CDS_LOCATION"U6W3"
SEC"1"
BOM_COST"SM_THERM"
SEC_TYPE"SOICLF"
PACK_TYPE"SOICLF"
ROOM"TEMP_SENSORS"
CDS_LIB"mstr_memory"
POWER_GROUP"VCC=P3V3_STBY;GND=GND;"
LOCATION"U6W3"
MATERIAL"IC"
PART_NUMBER"C47049-001";
"SDA"
$PN"5"39;
"WP"
$PN"7"41;
"SCL"
$PN"6"38;
"A0"
$PN"1"13;
"A1"
$PN"2"13;
"A2"
$PN"3"40;
%"RES"
"2","(-4850,3400)","2","mstr_discrete","I9";
;
CDS_SEC"1"
$SEC"1"
CDS_LOCATION"R6W9"
ROOM"CPU_FANS"
BOM_COST"SM_THERM"
CDS_LIB"mstr_discrete"
VALUE"4.75K"
WATTAGE"1/16W"
PART_NUMBER"G21796-072"
LOCATION"R6W9"
TOLERANCE"1%"
MATERIAL"CHIP"
PACK_TYPE"0402";
"A"
$PN"1"48;
"B"
$PN"2"2;
%"RES"
"2","(-3000,2200)","0","mstr_discrete","I90";
;
CDS_SEC"1"
CDS_LOCATION"R6W21"
ROOM"TEMP_SENSORS"
SEC"1"
BOM_COST"SM_THERM"
SEC_TYPE"0402"
CDS_LIB"mstr_discrete"
LOCATION"R6W21"
VALUE"1.00K"
TOLERANCE"1%"
WATTAGE"1/16W"
MATERIAL"CHIP"
PART_NUMBER"G21796-026"
PACK_TYPE"0402";
"A"
$PN"1"12;
"B"
$PN"2"40;
%"GND"
"1","(-2575,1275)","0","mstr_symbols","I91";
;
SIZE"1B"
CDS_LIB"mstr_symbols"
HDL_POWER"GND"
VOLTAGE"0.0V"
BODY_TYPE"PLUMBING";
"A\NAC"13;
%"RES"
"2","(-3000,1525)","0","mstr_discrete","I92";
;
CDS_SEC"1"
CDS_LOCATION"R6W23"
SEC_TYPE"0402"
BOM_COST"SM_THERM"
ROOM"TEMP_SENSORS"
SEC"1"
CDS_LIB"mstr_discrete"
TOLERANCE"1%"
VALUE"1.00K"
PACK_TYPE"0402"
MATERIAL"CHIP"
WATTAGE"1/16W"
PART_NUMBER"G21796-026"
LOCATION"R6W23";
"A"
$PN"1"41;
"B"
$PN"2"14;
%"GND"
"1","(-3000,1275)","0","mstr_symbols","I93";
;
HDL_POWER"GND"
CDS_LIB"mstr_symbols"
SIZE"1B"
VOLTAGE"0.0V"
BODY_TYPE"PLUMBING";
"A\NAC"14;
%"RES"
"1","(-3425,1750)","0","mstr_discrete","I94";
;
CDS_SEC"1"
CDS_LOCATION"R6W22"
SEC"1"
CDS_LIB"mstr_discrete"
ROOM"TEMP_SENSORS"
SEC_TYPE"0402"
BOM_COST"SM_THERM"
PART_NUMBER"G21796-173"
TOLERANCE"1%"
PACK_TYPE"0402"
LOCATION"R6W22"
VALUE"20.0"
WATTAGE"1/16W"
MATERIAL"CHIP";
"B"
$PN"2"38;
"A"
$PN"1"43;
%"PCA9555PWRG4-GP"
"1","(-2400,3600)","0","w_hdl","I97";
;
CDS_SEC"1"
$SEC"1"
CDS_LOCATION"U6W1"
PACK_TYPE"DISCRET-G5"
CDS_LIB"w_hdl"
CDS_LMAN_SYM_OUTLINE"-200,550,200,-550"
LOCATION"U6W1"
VALUE"PCA9555PWRG4-GP"
PART_NUMBER"71.09555.B0W";
"VCC"
$PN"24"16;
"SDA"
$PN"23"33;
"SCL"
$PN"22"32;
"A0"
$PN"21"31;
"P17"
$PN"20"0;
"P16"
$PN"19"0;
"P15"
$PN"18"0;
"P14"
$PN"17"0;
"P13"
$PN"16"0;
"P12"
$PN"15"0;
"P11"
$PN"14"30;
"P10"
$PN"13"29;
"GND"
$PN"12"4;
"P7"
$PN"11"20;
"P6"
$PN"10"28;
"P5"
$PN"9"18;
"P4"
$PN"8"27;
"P3"
$PN"7"26;
"P2"
$PN"6"25;
"P1"
$PN"5"24;
"P0"
$PN"4"23;
"A2"
$PN"3"17;
"A1"
$PN"2"22;
"INT#"
$PN"1"21;
END.
